(kicad_pcb
	(version 20260206)
	(generator "pcbnew")
	(generator_version "10.0")
	(general
		(thickness 1.6)
		(legacy_teardrops no)
	)
	(paper "A4")
	(title_block
		(title "03242023_DA0F0TMBIJ0_F0T_Motherboard_J_brd_V01_OCP.brd")
		(comment 1 "Grand Teton / footprints 5918-5924 of 6105")
	)
	(layers
		(0 "F.Cu" signal "TOP")
		(4 "In1.Cu" signal "GND")
		(6 "In2.Cu" signal "IN1")
		(8 "In3.Cu" signal "GND1")
		(10 "In4.Cu" signal "IN2")
		(12 "In5.Cu" signal "GND2")
		(14 "In6.Cu" signal "IN3")
		(16 "In7.Cu" signal "GND3")
		(18 "In8.Cu" signal "VCC")
		(20 "In9.Cu" signal "VCC1")
		(22 "In10.Cu" signal "GND4")
		(24 "In11.Cu" signal "IN4")
		(26 "In12.Cu" signal "GND5")
		(28 "In13.Cu" signal "IN5")
		(30 "In14.Cu" signal "GND6")
		(32 "In15.Cu" signal "IN6")
		(34 "In16.Cu" signal "GND7")
		(2 "B.Cu" signal "BOTTOM")
		(9 "F.Adhes" user "F.Adhesive")
		(11 "B.Adhes" user "B.Adhesive")
		(13 "F.Paste" user "Package Geometry/Pastemask Top")
		(15 "B.Paste" user "Package Geometry/Pastemask Bottom")
		(5 "F.SilkS" user "Ref Des/Silkscreen Top")
		(7 "B.SilkS" user "Ref Des/Silkscreen Bottom")
		(1 "F.Mask" user "Board Geometry/Soldermask Top")
		(3 "B.Mask" user "Board Geometry/Soldermask Bottom")
		(17 "Dwgs.User" user "User.Drawings")
		(19 "Cmts.User" user "User.Comments")
		(21 "Eco1.User" user "User.Eco1")
		(23 "Eco2.User" user "User.Eco2")
		(25 "Edge.Cuts" user "Board Geometry/Outline")
		(27 "Margin" user)
		(31 "F.CrtYd" user "Package Geometry/Place Bound Top")
		(29 "B.CrtYd" user "Package Geometry/Place Bound Bottom")
		(35 "F.Fab" user "Ref Des/Assembly Top")
		(33 "B.Fab" user "Ref Des/Assembly Bottom")
	)
	(footprint ""
		(layer "B.Cu")
		(at 176.317148 -358.09936 180)
		(property "Reference" "PC1683"
			(at 0 0 0)
			(layer "B.SilkS")
			(hide yes)
			(effects
				(font
					(size 1.27 1.27)
				)
				(justify mirror)
			)
		)
		(property "Value" ""
			(at 0 0 0)
			(layer "B.Fab")
			(effects
				(font
					(size 1.27 1.27)
				)
				(justify mirror)
			)
		)
		(duplicate_pad_numbers_are_jumpers no)
		(fp_line
			(start 1.524 0.762)
			(end 1.524 -0.762)
			(stroke
				(width 0.1524)
				(type default)
			)
			(layer "B.SilkS")
		)
		(fp_line
			(start 1.524 -0.762)
			(end -1.524 -0.762)
			(stroke
				(width 0.1524)
				(type default)
			)
			(layer "B.SilkS")
		)
		(fp_line
			(start -1.524 0.762)
			(end 1.524 0.762)
			(stroke
				(width 0.1524)
				(type default)
			)
			(layer "B.SilkS")
		)
		(fp_line
			(start -1.524 -0.762)
			(end -1.524 0.762)
			(stroke
				(width 0.1524)
				(type default)
			)
			(layer "B.SilkS")
		)
		(fp_line
			(start 1.1049 0.724916)
			(end -1.1049 0.724916)
			(stroke
				(width 0.1)
				(type default)
			)
			(layer "B.Fab")
		)
		(fp_line
			(start 1.1049 -0.724916)
			(end 1.1049 0.724916)
			(stroke
				(width 0.1)
				(type default)
			)
			(layer "B.Fab")
		)
		(fp_line
			(start -1.1049 0.724916)
			(end -1.1049 -0.724916)
			(stroke
				(width 0.1)
				(type default)
			)
			(layer "B.Fab")
		)
		(fp_line
			(start -1.1049 -0.724916)
			(end 1.1049 -0.724916)
			(stroke
				(width 0.1)
				(type default)
			)
			(layer "B.Fab")
		)
		(pad "1" smd rect
			(at 0.889 0 180)
			(size 1.016 1.27)
			(layers "B.Cu" "B.Mask" "B.Paste")
			(net "SW_P12V_PVCCFA_EHV_FIVRA_CPU1_R")
		)
		(pad "2" smd rect
			(at -0.889 0 180)
			(size 1.016 1.27)
			(layers "B.Cu" "B.Mask" "B.Paste")
			(net "GND")
		)
	)
	(footprint ""
		(layer "B.Cu")
		(at 297.525948 -48.409352)
		(property "Reference" "C1185"
			(at 0 0 0)
			(layer "B.SilkS")
			(hide yes)
			(effects
				(font
					(size 1.27 1.27)
				)
				(justify mirror)
			)
		)
		(property "Value" ""
			(at 0 0 0)
			(layer "B.Fab")
			(effects
				(font
					(size 1.27 1.27)
				)
				(justify mirror)
			)
		)
		(duplicate_pad_numbers_are_jumpers no)
		(fp_line
			(start -1.2954 -0.5842)
			(end -1.2954 0.5842)
			(stroke
				(width 0.1524)
				(type default)
			)
			(layer "B.SilkS")
		)
		(fp_line
			(start -1.2954 0.5842)
			(end 1.2954 0.5842)
			(stroke
				(width 0.1524)
				(type default)
			)
			(layer "B.SilkS")
		)
		(fp_line
			(start 0 -0.5842)
			(end 0 0.5842)
			(stroke
				(width 0.1524)
				(type default)
			)
			(layer "B.SilkS")
		)
		(fp_line
			(start 1.2954 -0.5842)
			(end -1.2954 -0.5842)
			(stroke
				(width 0.1524)
				(type default)
			)
			(layer "B.SilkS")
		)
		(fp_line
			(start 1.2954 0.5842)
			(end 1.2954 -0.5842)
			(stroke
				(width 0.1524)
				(type default)
			)
			(layer "B.SilkS")
		)
		(fp_line
			(start -1.1938 -0.4064)
			(end -1.1938 0.4064)
			(stroke
				(width 0.1)
				(type default)
			)
			(layer "B.Fab")
		)
		(fp_line
			(start -1.1938 0.4064)
			(end -0.8636 0.4064)
			(stroke
				(width 0.1)
				(type default)
			)
			(layer "B.Fab")
		)
		(fp_line
			(start -0.8636 -0.4572)
			(end -0.8636 -0.4064)
			(stroke
				(width 0.1)
				(type default)
			)
			(layer "B.Fab")
		)
		(fp_line
			(start -0.8636 -0.4064)
			(end -1.1938 -0.4064)
			(stroke
				(width 0.1)
				(type default)
			)
			(layer "B.Fab")
		)
		(fp_line
			(start -0.8636 0.4064)
			(end -0.8636 0.4572)
			(stroke
				(width 0.1)
				(type default)
			)
			(layer "B.Fab")
		)
		(fp_line
			(start -0.8636 0.4572)
			(end 0.8636 0.4572)
			(stroke
				(width 0.1)
				(type default)
			)
			(layer "B.Fab")
		)
		(fp_line
			(start 0.8636 -0.4572)
			(end -0.8636 -0.4572)
			(stroke
				(width 0.1)
				(type default)
			)
			(layer "B.Fab")
		)
		(fp_line
			(start 0.8636 -0.4064)
			(end 0.8636 -0.4572)
			(stroke
				(width 0.1)
				(type default)
			)
			(layer "B.Fab")
		)
		(fp_line
			(start 0.8636 0.4064)
			(end 1.1938 0.4064)
			(stroke
				(width 0.1)
				(type default)
			)
			(layer "B.Fab")
		)
		(fp_line
			(start 0.8636 0.4572)
			(end 0.8636 0.4064)
			(stroke
				(width 0.1)
				(type default)
			)
			(layer "B.Fab")
		)
		(fp_line
			(start 1.1938 -0.4064)
			(end 0.8636 -0.4064)
			(stroke
				(width 0.1)
				(type default)
			)
			(layer "B.Fab")
		)
		(fp_line
			(start 1.1938 0.4064)
			(end 1.1938 -0.4064)
			(stroke
				(width 0.1)
				(type default)
			)
			(layer "B.Fab")
		)
		(pad "1" smd rect
			(at 0.7366 0 270)
			(size 0.7112 0.8128)
			(layers "B.Cu" "B.Mask" "B.Paste")
			(net "P1V05_PCH_AUX")
		)
		(pad "2" smd rect
			(at -0.7366 0 270)
			(size 0.7112 0.8128)
			(layers "B.Cu" "B.Mask" "B.Paste")
			(net "GND")
		)
	)
	(footprint ""
		(layer "B.Cu")
		(at 169.506138 -193.01079 90)
		(property "Reference" "R151"
			(at 0 0 90)
			(layer "B.SilkS")
			(hide yes)
			(effects
				(font
					(size 1.27 1.27)
				)
				(justify mirror)
			)
		)
		(property "Value" ""
			(at 0 0 90)
			(layer "B.Fab")
			(effects
				(font
					(size 1.27 1.27)
				)
				(justify mirror)
			)
		)
		(duplicate_pad_numbers_are_jumpers no)
		(fp_line
			(start 0.7874 -0.4064)
			(end -0.7874 -0.4064)
			(stroke
				(width 0.1524)
				(type default)
			)
			(layer "B.SilkS")
		)
		(fp_line
			(start -0.7874 -0.4064)
			(end -0.7874 0.4064)
			(stroke
				(width 0.1524)
				(type default)
			)
			(layer "B.SilkS")
		)
		(fp_line
			(start 0.7874 0.4064)
			(end 0.7874 -0.4064)
			(stroke
				(width 0.1524)
				(type default)
			)
			(layer "B.SilkS")
		)
		(fp_line
			(start -0.7874 0.4064)
			(end 0.7874 0.4064)
			(stroke
				(width 0.1524)
				(type default)
			)
			(layer "B.SilkS")
		)
		(fp_line
			(start 0.67945 -0.305054)
			(end 0.12065 -0.305054)
			(stroke
				(width 0.1)
				(type default)
			)
			(layer "B.Fab")
		)
		(fp_line
			(start 0.12065 -0.305054)
			(end 0.12065 -0.2794)
			(stroke
				(width 0.1)
				(type default)
			)
			(layer "B.Fab")
		)
		(fp_line
			(start -0.12065 -0.3048)
			(end -0.67945 -0.3048)
			(stroke
				(width 0.1)
				(type default)
			)
			(layer "B.Fab")
		)
		(fp_line
			(start -0.67945 -0.3048)
			(end -0.67945 0.3048)
			(stroke
				(width 0.1)
				(type default)
			)
			(layer "B.Fab")
		)
		(fp_line
			(start 0.12065 -0.2794)
			(end -0.12065 -0.2794)
			(stroke
				(width 0.1)
				(type default)
			)
			(layer "B.Fab")
		)
		(fp_line
			(start -0.12065 -0.2794)
			(end -0.12065 -0.3048)
			(stroke
				(width 0.1)
				(type default)
			)
			(layer "B.Fab")
		)
		(fp_line
			(start 0.12065 0.2794)
			(end 0.12065 0.3048)
			(stroke
				(width 0.1)
				(type default)
			)
			(layer "B.Fab")
		)
		(fp_line
			(start -0.120396 0.2794)
			(end 0.12065 0.2794)
			(stroke
				(width 0.1)
				(type default)
			)
			(layer "B.Fab")
		)
		(fp_line
			(start 0.67945 0.3048)
			(end 0.67945 -0.305054)
			(stroke
				(width 0.1)
				(type default)
			)
			(layer "B.Fab")
		)
		(fp_line
			(start 0.12065 0.3048)
			(end 0.67945 0.3048)
			(stroke
				(width 0.1)
				(type default)
			)
			(layer "B.Fab")
		)
		(fp_line
			(start -0.120396 0.3048)
			(end -0.120396 0.2794)
			(stroke
				(width 0.1)
				(type default)
			)
			(layer "B.Fab")
		)
		(fp_line
			(start -0.67945 0.3048)
			(end -0.120396 0.3048)
			(stroke
				(width 0.1)
				(type default)
			)
			(layer "B.Fab")
		)
		(pad "1" smd circle
			(at 0.40005 0 270)
			(size 0 0)
			(layers "B.Cu" "B.Mask" "B.Paste")
			(net "PWRGD_DRAMPWRGD_CPU1_EF_LVC1_R2")
		)
		(pad "2" smd circle
			(at -0.40005 0 270)
			(size 0 0)
			(layers "B.Cu" "B.Mask" "B.Paste")
			(net "PVCCD_HV_CPU1")
		)
	)
	(footprint ""
		(layer "B.Cu")
		(at 107.887008 -212.049868 180)
		(property "Reference" "C460"
			(at 0 0 0)
			(layer "B.SilkS")
			(hide yes)
			(effects
				(font
					(size 1.27 1.27)
				)
				(justify mirror)
			)
		)
		(property "Value" ""
			(at 0 0 0)
			(layer "B.Fab")
			(effects
				(font
					(size 1.27 1.27)
				)
				(justify mirror)
			)
		)
		(duplicate_pad_numbers_are_jumpers no)
		(fp_line
			(start 1.524 0.762)
			(end 1.524 -0.762)
			(stroke
				(width 0.1524)
				(type default)
			)
			(layer "B.SilkS")
		)
		(fp_line
			(start 1.524 -0.762)
			(end -1.524 -0.762)
			(stroke
				(width 0.1524)
				(type default)
			)
			(layer "B.SilkS")
		)
		(fp_line
			(start -1.524 0.762)
			(end 1.524 0.762)
			(stroke
				(width 0.1524)
				(type default)
			)
			(layer "B.SilkS")
		)
		(fp_line
			(start -1.524 -0.762)
			(end -1.524 0.762)
			(stroke
				(width 0.1524)
				(type default)
			)
			(layer "B.SilkS")
		)
		(fp_line
			(start 1.1049 0.724916)
			(end -1.1049 0.724916)
			(stroke
				(width 0.1)
				(type default)
			)
			(layer "B.Fab")
		)
		(fp_line
			(start 1.1049 -0.724916)
			(end 1.1049 0.724916)
			(stroke
				(width 0.1)
				(type default)
			)
			(layer "B.Fab")
		)
		(fp_line
			(start -1.1049 0.724916)
			(end -1.1049 -0.724916)
			(stroke
				(width 0.1)
				(type default)
			)
			(layer "B.Fab")
		)
		(fp_line
			(start -1.1049 -0.724916)
			(end 1.1049 -0.724916)
			(stroke
				(width 0.1)
				(type default)
			)
			(layer "B.Fab")
		)
		(pad "1" smd rect
			(at 0.889 0 180)
			(size 1.016 1.27)
			(layers "B.Cu" "B.Mask" "B.Paste")
			(net "PVCCFA_EHV_CPU1")
		)
		(pad "2" smd rect
			(at -0.889 0 180)
			(size 1.016 1.27)
			(layers "B.Cu" "B.Mask" "B.Paste")
			(net "GND")
		)
	)
	(footprint ""
		(layer "B.Cu")
		(at 304.926238 -194.72021 90)
		(property "Reference" "R12"
			(at 0 0 90)
			(layer "B.SilkS")
			(hide yes)
			(effects
				(font
					(size 1.27 1.27)
				)
				(justify mirror)
			)
		)
		(property "Value" ""
			(at 0 0 90)
			(layer "B.Fab")
			(effects
				(font
					(size 1.27 1.27)
				)
				(justify mirror)
			)
		)
		(duplicate_pad_numbers_are_jumpers no)
		(fp_line
			(start 0.7874 -0.4064)
			(end -0.7874 -0.4064)
			(stroke
				(width 0.1524)
				(type default)
			)
			(layer "B.SilkS")
		)
		(fp_line
			(start -0.7874 -0.4064)
			(end -0.7874 0.4064)
			(stroke
				(width 0.1524)
				(type default)
			)
			(layer "B.SilkS")
		)
		(fp_line
			(start 0.7874 0.4064)
			(end 0.7874 -0.4064)
			(stroke
				(width 0.1524)
				(type default)
			)
			(layer "B.SilkS")
		)
		(fp_line
			(start -0.7874 0.4064)
			(end 0.7874 0.4064)
			(stroke
				(width 0.1524)
				(type default)
			)
			(layer "B.SilkS")
		)
		(fp_line
			(start 0.67945 -0.305054)
			(end 0.12065 -0.305054)
			(stroke
				(width 0.1)
				(type default)
			)
			(layer "B.Fab")
		)
		(fp_line
			(start 0.12065 -0.305054)
			(end 0.12065 -0.2794)
			(stroke
				(width 0.1)
				(type default)
			)
			(layer "B.Fab")
		)
		(fp_line
			(start -0.12065 -0.3048)
			(end -0.67945 -0.3048)
			(stroke
				(width 0.1)
				(type default)
			)
			(layer "B.Fab")
		)
		(fp_line
			(start -0.67945 -0.3048)
			(end -0.67945 0.3048)
			(stroke
				(width 0.1)
				(type default)
			)
			(layer "B.Fab")
		)
		(fp_line
			(start 0.12065 -0.2794)
			(end -0.12065 -0.2794)
			(stroke
				(width 0.1)
				(type default)
			)
			(layer "B.Fab")
		)
		(fp_line
			(start -0.12065 -0.2794)
			(end -0.12065 -0.3048)
			(stroke
				(width 0.1)
				(type default)
			)
			(layer "B.Fab")
		)
		(fp_line
			(start 0.12065 0.2794)
			(end 0.12065 0.3048)
			(stroke
				(width 0.1)
				(type default)
			)
			(layer "B.Fab")
		)
		(fp_line
			(start -0.120396 0.2794)
			(end 0.12065 0.2794)
			(stroke
				(width 0.1)
				(type default)
			)
			(layer "B.Fab")
		)
		(fp_line
			(start 0.67945 0.3048)
			(end 0.67945 -0.305054)
			(stroke
				(width 0.1)
				(type default)
			)
			(layer "B.Fab")
		)
		(fp_line
			(start 0.12065 0.3048)
			(end 0.67945 0.3048)
			(stroke
				(width 0.1)
				(type default)
			)
			(layer "B.Fab")
		)
		(fp_line
			(start -0.120396 0.3048)
			(end -0.120396 0.2794)
			(stroke
				(width 0.1)
				(type default)
			)
			(layer "B.Fab")
		)
		(fp_line
			(start -0.67945 0.3048)
			(end -0.120396 0.3048)
			(stroke
				(width 0.1)
				(type default)
			)
			(layer "B.Fab")
		)
		(pad "1" smd circle
			(at 0.40005 0 270)
			(size 0 0)
			(layers "B.Cu" "B.Mask" "B.Paste")
			(net "SVID_DIO0_CPU0")
		)
		(pad "2" smd circle
			(at -0.40005 0 270)
			(size 0 0)
			(layers "B.Cu" "B.Mask" "B.Paste")
			(net "SVID_DIO0_CPU0_R")
		)
	)
	(footprint ""
		(layer "B.Cu")
		(at 430.518316 -352.974148 -90)
		(property "Reference" "PC1185_P0_3"
			(at 0 0 90)
			(layer "B.SilkS")
			(hide yes)
			(effects
				(font
					(size 1.27 1.27)
				)
				(justify mirror)
			)
		)
		(property "Value" ""
			(at 0 0 90)
			(layer "B.Fab")
			(effects
				(font
					(size 1.27 1.27)
				)
				(justify mirror)
			)
		)
		(duplicate_pad_numbers_are_jumpers no)
		(fp_line
			(start -1.524 0.762)
			(end 1.524 0.762)
			(stroke
				(width 0.1524)
				(type default)
			)
			(layer "B.SilkS")
		)
		(fp_line
			(start 1.524 0.762)
			(end 1.524 -0.762)
			(stroke
				(width 0.1524)
				(type default)
			)
			(layer "B.SilkS")
		)
		(fp_line
			(start -1.524 -0.762)
			(end -1.524 0.762)
			(stroke
				(width 0.1524)
				(type default)
			)
			(layer "B.SilkS")
		)
		(fp_line
			(start 1.524 -0.762)
			(end -1.524 -0.762)
			(stroke
				(width 0.1524)
				(type default)
			)
			(layer "B.SilkS")
		)
		(fp_line
			(start -1.1049 0.724916)
			(end -1.1049 -0.724916)
			(stroke
				(width 0.1)
				(type default)
			)
			(layer "B.Fab")
		)
		(fp_line
			(start 1.1049 0.724916)
			(end -1.1049 0.724916)
			(stroke
				(width 0.1)
				(type default)
			)
			(layer "B.Fab")
		)
		(fp_line
			(start -1.1049 -0.724916)
			(end 1.1049 -0.724916)
			(stroke
				(width 0.1)
				(type default)
			)
			(layer "B.Fab")
		)
		(fp_line
			(start 1.1049 -0.724916)
			(end 1.1049 0.724916)
			(stroke
				(width 0.1)
				(type default)
			)
			(layer "B.Fab")
		)
		(pad "1" smd rect
			(at 0.889 0 270)
			(size 1.016 1.27)
			(layers "B.Cu" "B.Mask" "B.Paste")
			(net "PVCCFA_EHV_FIVRA_CPU0")
		)
		(pad "2" smd rect
			(at -0.889 0 270)
			(size 1.016 1.27)
			(layers "B.Cu" "B.Mask" "B.Paste")
			(net "GND")
		)
	)
	(footprint ""
		(layer "B.Cu")
		(at 109.125512 -415.047938 90)
		(property "Reference" "C2331"
			(at 0 0 90)
			(layer "B.SilkS")
			(hide yes)
			(effects
				(font
					(size 1.27 1.27)
				)
				(justify mirror)
			)
		)
		(property "Value" ""
			(at 0 0 90)
			(layer "B.Fab")
			(effects
				(font
					(size 1.27 1.27)
				)
				(justify mirror)
			)
		)
		(duplicate_pad_numbers_are_jumpers no)
		(fp_line
			(start 1.2954 -0.5842)
			(end -1.2954 -0.5842)
			(stroke
				(width 0.1524)
				(type default)
			)
			(layer "B.SilkS")
		)
		(fp_line
			(start 0 -0.5842)
			(end 0 0.5842)
			(stroke
				(width 0.1524)
				(type default)
			)
			(layer "B.SilkS")
		)
		(fp_line
			(start -1.2954 -0.5842)
			(end -1.2954 0.5842)
			(stroke
				(width 0.1524)
				(type default)
			)
			(layer "B.SilkS")
		)
		(fp_line
			(start 1.2954 0.5842)
			(end 1.2954 -0.5842)
			(stroke
				(width 0.1524)
				(type default)
			)
			(layer "B.SilkS")
		)
		(fp_line
			(start -1.2954 0.5842)
			(end 1.2954 0.5842)
			(stroke
				(width 0.1524)
				(type default)
			)
			(layer "B.SilkS")
		)
		(fp_line
			(start 0.8636 -0.4572)
			(end -0.8636 -0.4572)
			(stroke
				(width 0.1)
				(type default)
			)
			(layer "B.Fab")
		)
		(fp_line
			(start -0.8636 -0.4572)
			(end -0.8636 -0.4064)
			(stroke
				(width 0.1)
				(type default)
			)
			(layer "B.Fab")
		)
		(fp_line
			(start 1.1938 -0.4064)
			(end 0.8636 -0.4064)
			(stroke
				(width 0.1)
				(type default)
			)
			(layer "B.Fab")
		)
		(fp_line
			(start 0.8636 -0.4064)
			(end 0.8636 -0.4572)
			(stroke
				(width 0.1)
				(type default)
			)
			(layer "B.Fab")
		)
		(fp_line
			(start -0.8636 -0.4064)
			(end -1.1938 -0.4064)
			(stroke
				(width 0.1)
				(type default)
			)
			(layer "B.Fab")
		)
		(fp_line
			(start -1.1938 -0.4064)
			(end -1.1938 0.4064)
			(stroke
				(width 0.1)
				(type default)
			)
			(layer "B.Fab")
		)
		(fp_line
			(start 1.1938 0.4064)
			(end 1.1938 -0.4064)
			(stroke
				(width 0.1)
				(type default)
			)
			(layer "B.Fab")
		)
		(fp_line
			(start 0.8636 0.4064)
			(end 1.1938 0.4064)
			(stroke
				(width 0.1)
				(type default)
			)
			(layer "B.Fab")
		)
		(fp_line
			(start -0.8636 0.4064)
			(end -0.8636 0.4572)
			(stroke
				(width 0.1)
				(type default)
			)
			(layer "B.Fab")
		)
		(fp_line
			(start -1.1938 0.4064)
			(end -0.8636 0.4064)
			(stroke
				(width 0.1)
				(type default)
			)
			(layer "B.Fab")
		)
		(fp_line
			(start 0.8636 0.4572)
			(end 0.8636 0.4064)
			(stroke
				(width 0.1)
				(type default)
			)
			(layer "B.Fab")
		)
		(fp_line
			(start -0.8636 0.4572)
			(end 0.8636 0.4572)
			(stroke
				(width 0.1)
				(type default)
			)
			(layer "B.Fab")
		)
		(pad "1" smd rect
			(at 0.7366 0)
			(size 0.7112 0.8128)
			(layers "B.Cu" "B.Mask" "B.Paste")
			(net "P3V3_9ZXL045_VDDA")
		)
		(pad "2" smd rect
			(at -0.7366 0)
			(size 0.7112 0.8128)
			(layers "B.Cu" "B.Mask" "B.Paste")
			(net "GND")
		)
	)
)
